(kicad_pcb
	(version 20260206)
	(generator "pcbnew")
	(generator_version "10.0")
	(general
		(thickness 1.6)
		(legacy_teardrops no)
	)
	(paper "A4")
	(title_block
		(title "baseboard — 13948-1b.1110WZS1818.brd")
		(comment 1 "Honey Badger (Wiwynn) / footprints 441-448 of 2523")
	)
	(layers
		(0 "F.Cu" signal "TOP")
		(4 "In1.Cu" signal "L2GND")
		(6 "In2.Cu" signal "L3")
		(8 "In3.Cu" signal "L4VCC")
		(10 "In4.Cu" signal "L5VCC")
		(12 "In5.Cu" signal "L6")
		(14 "In6.Cu" signal "L7GND")
		(2 "B.Cu" signal "BOTTOM")
		(9 "F.Adhes" user "F.Adhesive")
		(11 "B.Adhes" user "B.Adhesive")
		(13 "F.Paste" user "Package Geometry/Pastemask Top")
		(15 "B.Paste" user "Package Geometry/Pastemask Bottom")
		(5 "F.SilkS" user "Ref Des/Silkscreen Top")
		(7 "B.SilkS" user "Ref Des/Silkscreen Bottom")
		(1 "F.Mask" user "Board Geometry/Soldermask Top")
		(3 "B.Mask" user "Board Geometry/Soldermask Bottom")
		(17 "Dwgs.User" user "User.Drawings")
		(19 "Cmts.User" user "User.Comments")
		(21 "Eco1.User" user "User.Eco1")
		(23 "Eco2.User" user "User.Eco2")
		(25 "Edge.Cuts" user "Board Geometry/Outline")
		(27 "Margin" user)
		(31 "F.CrtYd" user "Package Geometry/Place Bound Top")
		(29 "B.CrtYd" user "Package Geometry/Place Bound Bottom")
		(35 "F.Fab" user "Ref Des/Assembly Top")
		(33 "B.Fab" user "Ref Des/Assembly Bottom")
	)
	(footprint ""
		(layer "F.Cu")
		(at 75.184 -22.733 180)
		(property "Reference" "PR195"
			(at 0 0 180)
			(layer "F.SilkS")
			(hide yes)
			(effects
				(font
					(size 1.27 1.27)
				)
			)
		)
		(property "Value" "0R2J-2-GP"
			(at 0.064008 -3.993896 180)
			(unlocked yes)
			(layer "F.Fab")
			(hide yes)
			(effects
				(font
					(size 1.016 1.016)
					(thickness 0.1524)
				)
			)
		)
		(property "Device Type" "R402H16"
			(at 0.064008 -5.517896 180)
			(unlocked yes)
			(layer "F.Fab")
			(hide yes)
			(effects
				(font
					(size 1.016 1.016)
					(thickness 0.1524)
				)
			)
		)
		(duplicate_pad_numbers_are_jumpers no)
		(fp_line
			(start 0.508 -0.9398)
			(end -0.508 -0.9398)
			(stroke
				(width 0.1524)
				(type default)
			)
			(layer "F.SilkS")
		)
		(fp_line
			(start -0.508 -0.9398)
			(end -0.508 0.9398)
			(stroke
				(width 0.1524)
				(type default)
			)
			(layer "F.SilkS")
		)
		(fp_rect
			(start -0.508 0.9398)
			(end 0.508 -0.9398)
			(stroke
				(width 0)
				(type default)
			)
			(fill no)
			(layer "F.CrtYd")
		)
		(fp_rect
			(start -0.508 0.9398)
			(end 0.508 -0.9398)
			(stroke
				(width 0)
				(type default)
			)
			(fill no)
			(layer "F.Fab")
		)
		(pad "1" smd custom
			(at 0 -0.4445 180)
			(size 0.1397 0.1397)
			(layers "F.Cu" "F.Mask" "F.Paste")
			(net "VT235_EN")
			(options
				(clearance outline)
				(anchor circle)
			)
			(primitives
				(gr_poly
					(pts
						(arc
							(start -0.1778 -0.2794)
							(mid -0.249642 -0.249642)
							(end -0.2794 -0.1778)
						)
						(arc
							(start -0.2794 0.1778)
							(mid -0.249642 0.249642)
							(end -0.1778 0.2794)
						)
						(arc
							(start 0.1778 0.2794)
							(mid 0.249642 0.249642)
							(end 0.2794 0.1778)
						)
						(arc
							(start 0.2794 -0.1778)
							(mid 0.249642 -0.249642)
							(end 0.1778 -0.2794)
						)
					)
					(width 0)
					(fill yes)
				)
			)
		)
		(pad "2" smd custom
			(at 0 0.4445 180)
			(size 0.1397 0.1397)
			(layers "F.Cu" "F.Mask" "F.Paste")
			(net "BMC_EN_0V955_C")
			(options
				(clearance outline)
				(anchor circle)
			)
			(primitives
				(gr_poly
					(pts
						(arc
							(start -0.1778 -0.2794)
							(mid -0.249642 -0.249642)
							(end -0.2794 -0.1778)
						)
						(arc
							(start -0.2794 0.1778)
							(mid -0.249642 0.249642)
							(end -0.1778 0.2794)
						)
						(arc
							(start 0.1778 0.2794)
							(mid 0.249642 0.249642)
							(end 0.2794 0.1778)
						)
						(arc
							(start 0.2794 -0.1778)
							(mid 0.249642 -0.249642)
							(end 0.1778 -0.2794)
						)
					)
					(width 0)
					(fill yes)
				)
			)
		)
	)
	(footprint ""
		(layer "F.Cu")
		(at 24.580088 -181.865016)
		(property "Reference" "SR304"
			(at 0 0 0)
			(layer "F.SilkS")
			(hide yes)
			(effects
				(font
					(size 1.27 1.27)
				)
			)
		)
		(property "Value" "0R2J-2-GP"
			(at 0.064008 -3.993896 0)
			(unlocked yes)
			(layer "F.Fab")
			(hide yes)
			(effects
				(font
					(size 1.016 1.016)
					(thickness 0.1524)
				)
			)
		)
		(property "Device Type" "R402H16"
			(at 0.064008 -5.517896 0)
			(unlocked yes)
			(layer "F.Fab")
			(hide yes)
			(effects
				(font
					(size 1.016 1.016)
					(thickness 0.1524)
				)
			)
		)
		(duplicate_pad_numbers_are_jumpers no)
		(fp_line
			(start -0.508 -0.9398)
			(end -0.508 0.9398)
			(stroke
				(width 0.1524)
				(type default)
			)
			(layer "F.SilkS")
		)
		(fp_line
			(start 0.508 -0.9398)
			(end -0.508 -0.9398)
			(stroke
				(width 0.1524)
				(type default)
			)
			(layer "F.SilkS")
		)
		(fp_rect
			(start -0.508 0.9398)
			(end 0.508 -0.9398)
			(stroke
				(width 0)
				(type default)
			)
			(fill no)
			(layer "F.CrtYd")
		)
		(fp_rect
			(start -0.508 0.9398)
			(end 0.508 -0.9398)
			(stroke
				(width 0)
				(type default)
			)
			(fill no)
			(layer "F.Fab")
		)
		(pad "1" smd custom
			(at 0 -0.4445)
			(size 0.1397 0.1397)
			(layers "F.Cu" "F.Mask" "F.Paste")
			(net "PRE_SCL")
			(options
				(clearance outline)
				(anchor circle)
			)
			(primitives
				(gr_poly
					(pts
						(arc
							(start -0.1778 -0.2794)
							(mid -0.249642 -0.249642)
							(end -0.2794 -0.1778)
						)
						(arc
							(start -0.2794 0.1778)
							(mid -0.249642 0.249642)
							(end -0.1778 0.2794)
						)
						(arc
							(start 0.1778 0.2794)
							(mid 0.249642 0.249642)
							(end 0.2794 0.1778)
						)
						(arc
							(start 0.2794 -0.1778)
							(mid 0.249642 -0.249642)
							(end 0.1778 -0.2794)
						)
					)
					(width 0)
					(fill yes)
				)
			)
		)
		(pad "2" smd custom
			(at 0 0.4445)
			(size 0.1397 0.1397)
			(layers "F.Cu" "F.Mask" "F.Paste")
			(net "BMC_IOEXP_SCL_10")
			(options
				(clearance outline)
				(anchor circle)
			)
			(primitives
				(gr_poly
					(pts
						(arc
							(start -0.1778 -0.2794)
							(mid -0.249642 -0.249642)
							(end -0.2794 -0.1778)
						)
						(arc
							(start -0.2794 0.1778)
							(mid -0.249642 0.249642)
							(end -0.1778 0.2794)
						)
						(arc
							(start 0.1778 0.2794)
							(mid 0.249642 0.249642)
							(end 0.2794 0.1778)
						)
						(arc
							(start 0.2794 -0.1778)
							(mid 0.249642 -0.249642)
							(end 0.1778 -0.2794)
						)
					)
					(width 0)
					(fill yes)
				)
			)
		)
	)
	(footprint ""
		(layer "F.Cu")
		(at 184.404 -224.155 90)
		(property "Reference" "R1578"
			(at 0 0 90)
			(layer "F.SilkS")
			(hide yes)
			(effects
				(font
					(size 1.27 1.27)
				)
			)
		)
		(property "Value" "10KR2F-2-GP"
			(at 0.064008 -3.993896 90)
			(unlocked yes)
			(layer "F.Fab")
			(hide yes)
			(effects
				(font
					(size 1.016 1.016)
					(thickness 0.1524)
				)
			)
		)
		(property "Device Type" "R402H16"
			(at 0.064008 -5.517896 90)
			(unlocked yes)
			(layer "F.Fab")
			(hide yes)
			(effects
				(font
					(size 1.016 1.016)
					(thickness 0.1524)
				)
			)
		)
		(duplicate_pad_numbers_are_jumpers no)
		(fp_line
			(start 0.508 -0.9398)
			(end -0.508 -0.9398)
			(stroke
				(width 0.1524)
				(type default)
			)
			(layer "F.SilkS")
		)
		(fp_line
			(start -0.508 -0.9398)
			(end -0.508 0.9398)
			(stroke
				(width 0.1524)
				(type default)
			)
			(layer "F.SilkS")
		)
		(fp_rect
			(start -0.508 0.9398)
			(end 0.508 -0.9398)
			(stroke
				(width 0)
				(type default)
			)
			(fill no)
			(layer "F.CrtYd")
		)
		(fp_rect
			(start -0.508 0.9398)
			(end 0.508 -0.9398)
			(stroke
				(width 0)
				(type default)
			)
			(fill no)
			(layer "F.Fab")
		)
		(pad "1" smd custom
			(at 0 -0.4445 90)
			(size 0.1397 0.1397)
			(layers "F.Cu" "F.Mask" "F.Paste")
			(net "P3V3_STBY")
			(options
				(clearance outline)
				(anchor circle)
			)
			(primitives
				(gr_poly
					(pts
						(arc
							(start -0.1778 -0.2794)
							(mid -0.249642 -0.249642)
							(end -0.2794 -0.1778)
						)
						(arc
							(start -0.2794 0.1778)
							(mid -0.249642 0.249642)
							(end -0.1778 0.2794)
						)
						(arc
							(start 0.1778 0.2794)
							(mid 0.249642 0.249642)
							(end 0.2794 0.1778)
						)
						(arc
							(start 0.2794 -0.1778)
							(mid 0.249642 -0.249642)
							(end 0.1778 -0.2794)
						)
					)
					(width 0)
					(fill yes)
				)
			)
		)
		(pad "2" smd custom
			(at 0 0.4445 90)
			(size 0.1397 0.1397)
			(layers "F.Cu" "F.Mask" "F.Paste")
			(net "PWRBTN_FP_N")
			(options
				(clearance outline)
				(anchor circle)
			)
			(primitives
				(gr_poly
					(pts
						(arc
							(start -0.1778 -0.2794)
							(mid -0.249642 -0.249642)
							(end -0.2794 -0.1778)
						)
						(arc
							(start -0.2794 0.1778)
							(mid -0.249642 0.249642)
							(end -0.1778 0.2794)
						)
						(arc
							(start 0.1778 0.2794)
							(mid 0.249642 0.249642)
							(end 0.2794 0.1778)
						)
						(arc
							(start 0.2794 -0.1778)
							(mid 0.249642 -0.249642)
							(end 0.1778 -0.2794)
						)
					)
					(width 0)
					(fill yes)
				)
			)
		)
	)
	(footprint ""
		(layer "F.Cu")
		(at 256.413 -122.047 -90)
		(property "Reference" "C340"
			(at 0 0 270)
			(layer "F.SilkS")
			(hide yes)
			(effects
				(font
					(size 1.27 1.27)
				)
			)
		)
		(property "Value" "SCD1U25V2KX-2-GP"
			(at 1.1811 -2.7051 270)
			(unlocked yes)
			(layer "F.Fab")
			(hide yes)
			(effects
				(font
					(size 1.016 1.016)
					(thickness 0.1524)
				)
			)
		)
		(property "Device Type" "C402H22"
			(at 1.1811 -4.2291 270)
			(unlocked yes)
			(layer "F.Fab")
			(hide yes)
			(effects
				(font
					(size 1.016 1.016)
					(thickness 0.1524)
				)
			)
		)
		(duplicate_pad_numbers_are_jumpers no)
		(fp_rect
			(start -0.4318 0.9525)
			(end 0.4318 -0.9525)
			(stroke
				(width 0)
				(type default)
			)
			(fill no)
			(layer "F.CrtYd")
		)
		(fp_rect
			(start -0.4318 0.9525)
			(end 0.4318 -0.9525)
			(stroke
				(width 0)
				(type default)
			)
			(fill no)
			(layer "F.Fab")
		)
		(pad "1" smd custom
			(at 0 -0.4445 270)
			(size 0.1524 0.1524)
			(layers "F.Cu" "F.Mask" "F.Paste")
			(net "P3V3_STBY")
			(options
				(clearance outline)
				(anchor circle)
			)
			(primitives
				(gr_poly
					(pts
						(arc
							(start 0.3048 -0.2032)
							(mid 0.275042 -0.275042)
							(end 0.2032 -0.3048)
						)
						(arc
							(start -0.2032 -0.3048)
							(mid -0.275042 -0.275042)
							(end -0.3048 -0.2032)
						)
						(arc
							(start -0.3048 0.2032)
							(mid -0.275042 0.275042)
							(end -0.2032 0.3048)
						)
						(arc
							(start 0.2032 0.3048)
							(mid 0.275042 0.275042)
							(end 0.3048 0.2032)
						)
					)
					(width 0)
					(fill yes)
				)
			)
		)
		(pad "2" smd custom
			(at 0 0.4445 270)
			(size 0.1524 0.1524)
			(layers "F.Cu" "F.Mask" "F.Paste")
			(net "GND")
			(options
				(clearance outline)
				(anchor circle)
			)
			(primitives
				(gr_poly
					(pts
						(arc
							(start 0.3048 -0.2032)
							(mid 0.275042 -0.275042)
							(end 0.2032 -0.3048)
						)
						(arc
							(start -0.2032 -0.3048)
							(mid -0.275042 -0.275042)
							(end -0.3048 -0.2032)
						)
						(arc
							(start -0.3048 0.2032)
							(mid -0.275042 0.275042)
							(end -0.2032 0.3048)
						)
						(arc
							(start 0.2032 0.3048)
							(mid 0.275042 0.275042)
							(end 0.3048 0.2032)
						)
					)
					(width 0)
					(fill yes)
				)
			)
		)
	)
	(footprint ""
		(layer "F.Cu")
		(at 184.776872 -202.560936 90)
		(property "Reference" "R426"
			(at 0 0 90)
			(layer "F.SilkS")
			(hide yes)
			(effects
				(font
					(size 1.27 1.27)
				)
			)
		)
		(property "Value" "10KR2F-2-GP"
			(at 0.064008 -3.993896 90)
			(unlocked yes)
			(layer "F.Fab")
			(hide yes)
			(effects
				(font
					(size 1.016 1.016)
					(thickness 0.1524)
				)
			)
		)
		(property "Device Type" "R402H16"
			(at 0.064008 -5.517896 90)
			(unlocked yes)
			(layer "F.Fab")
			(hide yes)
			(effects
				(font
					(size 1.016 1.016)
					(thickness 0.1524)
				)
			)
		)
		(duplicate_pad_numbers_are_jumpers no)
		(fp_line
			(start 0.508 -0.9398)
			(end -0.508 -0.9398)
			(stroke
				(width 0.1524)
				(type default)
			)
			(layer "F.SilkS")
		)
		(fp_line
			(start -0.508 -0.9398)
			(end -0.508 0.9398)
			(stroke
				(width 0.1524)
				(type default)
			)
			(layer "F.SilkS")
		)
		(fp_rect
			(start -0.508 0.9398)
			(end 0.508 -0.9398)
			(stroke
				(width 0)
				(type default)
			)
			(fill no)
			(layer "F.CrtYd")
		)
		(fp_rect
			(start -0.508 0.9398)
			(end 0.508 -0.9398)
			(stroke
				(width 0)
				(type default)
			)
			(fill no)
			(layer "F.Fab")
		)
		(pad "1" smd custom
			(at 0 -0.4445 90)
			(size 0.1397 0.1397)
			(layers "F.Cu" "F.Mask" "F.Paste")
			(net "I2C_B_BUF_READY")
			(options
				(clearance outline)
				(anchor circle)
			)
			(primitives
				(gr_poly
					(pts
						(arc
							(start -0.1778 -0.2794)
							(mid -0.249642 -0.249642)
							(end -0.2794 -0.1778)
						)
						(arc
							(start -0.2794 0.1778)
							(mid -0.249642 0.249642)
							(end -0.1778 0.2794)
						)
						(arc
							(start 0.1778 0.2794)
							(mid 0.249642 0.249642)
							(end 0.2794 0.1778)
						)
						(arc
							(start 0.2794 -0.1778)
							(mid 0.249642 -0.249642)
							(end 0.1778 -0.2794)
						)
					)
					(width 0)
					(fill yes)
				)
			)
		)
		(pad "2" smd custom
			(at 0 0.4445 90)
			(size 0.1397 0.1397)
			(layers "F.Cu" "F.Mask" "F.Paste")
			(net "P3V3_STBY")
			(options
				(clearance outline)
				(anchor circle)
			)
			(primitives
				(gr_poly
					(pts
						(arc
							(start -0.1778 -0.2794)
							(mid -0.249642 -0.249642)
							(end -0.2794 -0.1778)
						)
						(arc
							(start -0.2794 0.1778)
							(mid -0.249642 0.249642)
							(end -0.1778 0.2794)
						)
						(arc
							(start 0.1778 0.2794)
							(mid 0.249642 0.249642)
							(end 0.2794 0.1778)
						)
						(arc
							(start 0.2794 -0.1778)
							(mid 0.249642 -0.249642)
							(end 0.1778 -0.2794)
						)
					)
					(width 0)
					(fill yes)
				)
			)
		)
	)
	(footprint ""
		(layer "F.Cu")
		(at 311.277 -201.041)
		(property "Reference" "R172"
			(at 0 0 0)
			(layer "F.SilkS")
			(hide yes)
			(effects
				(font
					(size 1.27 1.27)
				)
			)
		)
		(property "Value" "4K7R2J-2-GP"
			(at 0.064008 -3.993896 0)
			(unlocked yes)
			(layer "F.Fab")
			(hide yes)
			(effects
				(font
					(size 1.016 1.016)
					(thickness 0.1524)
				)
			)
		)
		(property "Device Type" "R402H16"
			(at 0.064008 -5.517896 0)
			(unlocked yes)
			(layer "F.Fab")
			(hide yes)
			(effects
				(font
					(size 1.016 1.016)
					(thickness 0.1524)
				)
			)
		)
		(duplicate_pad_numbers_are_jumpers no)
		(fp_line
			(start -0.508 -0.9398)
			(end -0.508 0.9398)
			(stroke
				(width 0.1524)
				(type default)
			)
			(layer "F.SilkS")
		)
		(fp_line
			(start 0.508 -0.9398)
			(end -0.508 -0.9398)
			(stroke
				(width 0.1524)
				(type default)
			)
			(layer "F.SilkS")
		)
		(fp_rect
			(start -0.508 0.9398)
			(end 0.508 -0.9398)
			(stroke
				(width 0)
				(type default)
			)
			(fill no)
			(layer "F.CrtYd")
		)
		(fp_rect
			(start -0.508 0.9398)
			(end 0.508 -0.9398)
			(stroke
				(width 0)
				(type default)
			)
			(fill no)
			(layer "F.Fab")
		)
		(pad "1" smd custom
			(at 0 -0.4445)
			(size 0.1397 0.1397)
			(layers "F.Cu" "F.Mask" "F.Paste")
			(net "P3V3_STBY")
			(options
				(clearance outline)
				(anchor circle)
			)
			(primitives
				(gr_poly
					(pts
						(arc
							(start -0.1778 -0.2794)
							(mid -0.249642 -0.249642)
							(end -0.2794 -0.1778)
						)
						(arc
							(start -0.2794 0.1778)
							(mid -0.249642 0.249642)
							(end -0.1778 0.2794)
						)
						(arc
							(start 0.1778 0.2794)
							(mid 0.249642 0.249642)
							(end 0.2794 0.1778)
						)
						(arc
							(start 0.2794 -0.1778)
							(mid 0.249642 -0.249642)
							(end 0.1778 -0.2794)
						)
					)
					(width 0)
					(fill yes)
				)
			)
		)
		(pad "2" smd custom
			(at 0 0.4445)
			(size 0.1397 0.1397)
			(layers "F.Cu" "F.Mask" "F.Paste")
			(net "LED_DR_RESET#")
			(options
				(clearance outline)
				(anchor circle)
			)
			(primitives
				(gr_poly
					(pts
						(arc
							(start -0.1778 -0.2794)
							(mid -0.249642 -0.249642)
							(end -0.2794 -0.1778)
						)
						(arc
							(start -0.2794 0.1778)
							(mid -0.249642 0.249642)
							(end -0.1778 0.2794)
						)
						(arc
							(start 0.1778 0.2794)
							(mid 0.249642 0.249642)
							(end 0.2794 0.1778)
						)
						(arc
							(start 0.2794 -0.1778)
							(mid 0.249642 -0.249642)
							(end 0.1778 -0.2794)
						)
					)
					(width 0)
					(fill yes)
				)
			)
		)
	)
	(footprint ""
		(layer "F.Cu")
		(at 174.353728 -32.515048)
		(property "Reference" "R386"
			(at 0 0 0)
			(layer "F.SilkS")
			(hide yes)
			(effects
				(font
					(size 1.27 1.27)
				)
			)
		)
		(property "Value" "0R2J-2-GP"
			(at 0.064008 -3.993896 0)
			(unlocked yes)
			(layer "F.Fab")
			(hide yes)
			(effects
				(font
					(size 1.016 1.016)
					(thickness 0.1524)
				)
			)
		)
		(property "Device Type" "R402H16"
			(at 0.064008 -5.517896 0)
			(unlocked yes)
			(layer "F.Fab")
			(hide yes)
			(effects
				(font
					(size 1.016 1.016)
					(thickness 0.1524)
				)
			)
		)
		(duplicate_pad_numbers_are_jumpers no)
		(fp_line
			(start -0.508 -0.9398)
			(end -0.508 0.9398)
			(stroke
				(width 0.1524)
				(type default)
			)
			(layer "F.SilkS")
		)
		(fp_line
			(start 0.508 -0.9398)
			(end -0.508 -0.9398)
			(stroke
				(width 0.1524)
				(type default)
			)
			(layer "F.SilkS")
		)
		(fp_rect
			(start -0.508 0.9398)
			(end 0.508 -0.9398)
			(stroke
				(width 0)
				(type default)
			)
			(fill no)
			(layer "F.CrtYd")
		)
		(fp_rect
			(start -0.508 0.9398)
			(end 0.508 -0.9398)
			(stroke
				(width 0)
				(type default)
			)
			(fill no)
			(layer "F.Fab")
		)
		(pad "1" smd custom
			(at 0 -0.4445)
			(size 0.1397 0.1397)
			(layers "F.Cu" "F.Mask" "F.Paste")
			(net "BCM5221_MB_RX_DN")
			(options
				(clearance outline)
				(anchor circle)
			)
			(primitives
				(gr_poly
					(pts
						(arc
							(start -0.1778 -0.2794)
							(mid -0.249642 -0.249642)
							(end -0.2794 -0.1778)
						)
						(arc
							(start -0.2794 0.1778)
							(mid -0.249642 0.249642)
							(end -0.1778 0.2794)
						)
						(arc
							(start 0.1778 0.2794)
							(mid 0.249642 0.249642)
							(end 0.2794 0.1778)
						)
						(arc
							(start 0.2794 -0.1778)
							(mid 0.249642 -0.249642)
							(end 0.1778 -0.2794)
						)
					)
					(width 0)
					(fill yes)
				)
			)
		)
		(pad "2" smd custom
			(at 0 0.4445)
			(size 0.1397 0.1397)
			(layers "F.Cu" "F.Mask" "F.Paste")
			(net "BCM5221_RX_C_DN")
			(options
				(clearance outline)
				(anchor circle)
			)
			(primitives
				(gr_poly
					(pts
						(arc
							(start -0.1778 -0.2794)
							(mid -0.249642 -0.249642)
							(end -0.2794 -0.1778)
						)
						(arc
							(start -0.2794 0.1778)
							(mid -0.249642 0.249642)
							(end -0.1778 0.2794)
						)
						(arc
							(start 0.1778 0.2794)
							(mid 0.249642 0.249642)
							(end 0.2794 0.1778)
						)
						(arc
							(start 0.2794 -0.1778)
							(mid 0.249642 -0.249642)
							(end 0.1778 -0.2794)
						)
					)
					(width 0)
					(fill yes)
				)
			)
		)
	)
	(footprint ""
		(layer "F.Cu")
		(at 113.792 -77.343)
		(property "Reference" "STP73"
			(at 0 0 0)
			(layer "F.SilkS")
			(hide yes)
			(effects
				(font
					(size 1.27 1.27)
				)
			)
		)
		(property "Value" "TPAD28"
			(at 0.0127 -1.8034 0)
			(unlocked yes)
			(layer "F.Fab")
			(hide yes)
			(effects
				(font
					(size 1.016 1.016)
					(thickness 0.1524)
				)
			)
		)
		(property "Device Type" "TPAD28"
			(at 0.0127 -3.3274 0)
			(unlocked yes)
			(layer "F.Fab")
			(hide yes)
			(effects
				(font
					(size 1.016 1.016)
					(thickness 0.1524)
				)
			)
		)
		(duplicate_pad_numbers_are_jumpers no)
		(fp_poly
			(pts
				(arc
					(start 0.3556 0)
					(mid -0.3556 0)
					(end 0.3556 0)
				)
			)
			(stroke
				(width 0)
				(type default)
			)
			(fill no)
			(layer "F.CrtYd")
		)
		(fp_poly
			(pts
				(arc
					(start 0.6096 0)
					(mid -0.6096 0)
					(end 0.6096 0)
				)
			)
			(stroke
				(width 0)
				(type default)
			)
			(fill no)
			(layer "F.Fab")
		)
		(pad "1" smd circle
			(at 0 0)
			(size 0.7112 0.7112)
			(layers "F.Cu" "F.Mask" "F.Paste")
			(net "EXP_TEST_MUX34")
		)
	)
)
